# SCM (Grand Teton) — schematic netlist excerpt (pin names and nets, part order shuffled) for the footprints in the layout excerpt that follows; sources: Cadence DE-HDL packaged netlist, KiCad conversion of 12092022_DA0F0TMDCD0_F0T_Management_Board_D_brd_V3_OCP.brd

U52  74LVC1G08GW  IC  pkg SM  page 55
  B  = PWRGD_P5V_AUX
  A  = PWRGD_P3V3_RGM
  GND  = GND
  Y  = EN_P1V2_AUX
  VCC  = P3V3_LDO

X2  TP_TDR_4P_FTS  TP_TDR_4P_DIP EMPTY  pkg TH  page 60
  S1  = TDR_DIFF_85_IN1_DP
  P1  = GND_P1
  P2  = GND_P1
  S2  = TDR_DIFF_85_IN1_DN

(kicad_pcb
	(version 20260206)
	(generator "pcbnew")
	(generator_version "10.0")
	(general
		(thickness 1.6)
		(legacy_teardrops no)
	)
	(paper "A4")
	(title_block
		(title "12092022_DA0F0TMDCD0_F0T_Management_Board_D_brd_V3_OCP.brd")
		(comment 1 "Grand Teton / footprints 819-820 of 1440")
	)
	(layers
		(0 "F.Cu" signal "TOP")
		(4 "In1.Cu" signal "GND")
		(6 "In2.Cu" signal "IN1")
		(8 "In3.Cu" signal "GND1")
		(10 "In4.Cu" signal "IN2")
		(12 "In5.Cu" signal "VCC")
		(14 "In6.Cu" signal "VCC1")
		(16 "In7.Cu" signal "IN3")
		(18 "In8.Cu" signal "GND2")
		(20 "In9.Cu" signal "IN4")
		(22 "In10.Cu" signal "GND3")
		(2 "B.Cu" signal "BOTTOM")
		(9 "F.Adhes" user "F.Adhesive")
		(11 "B.Adhes" user "B.Adhesive")
		(13 "F.Paste" user "Package Geometry/Pastemask Top")
		(15 "B.Paste" user "Package Geometry/Pastemask Bottom")
		(5 "F.SilkS" user "Ref Des/Silkscreen Top")
		(7 "B.SilkS" user "Ref Des/Silkscreen Bottom")
		(1 "F.Mask" user "Board Geometry/Soldermask Top")
		(3 "B.Mask" user "Board Geometry/Soldermask Bottom")
		(17 "Dwgs.User" user "User.Drawings")
		(19 "Cmts.User" user "User.Comments")
		(21 "Eco1.User" user "User.Eco1")
		(23 "Eco2.User" user "User.Eco2")
		(25 "Edge.Cuts" user "Board Geometry/Outline")
		(27 "Margin" user)
		(31 "F.CrtYd" user "Package Geometry/Place Bound Top")
		(29 "B.CrtYd" user "Package Geometry/Place Bound Bottom")
		(35 "F.Fab" user "Ref Des/Assembly Top")
		(33 "B.Fab" user "Ref Des/Assembly Bottom")
	)
	(footprint ""
		(layer "B.Cu")
		(at 79.7814 -68.6562 90)
		(property "Reference" "U52"
			(at -0.2794 1.97993 270)
			(unlocked yes)
			(layer "B.SilkS")
			(effects
				(font
					(size 0.7874 0.5842)
					(thickness 0.1524)
				)
				(justify mirror)
			)
		)
		(property "Value" ""
			(at 0 0 90)
			(layer "B.Fab")
			(effects
				(font
					(size 1.27 1.27)
				)
				(justify mirror)
			)
		)
		(duplicate_pad_numbers_are_jumpers no)
		(fp_line
			(start 0.254 -1.1176)
			(end 1.7018 -1.1176)
			(stroke
				(width 0.1524)
				(type default)
			)
			(layer "B.SilkS")
		)
		(fp_line
			(start -0.254 -1.1176)
			(end 0 -0.7112)
			(stroke
				(width 0.1524)
				(type default)
			)
			(layer "B.SilkS")
		)
		(fp_line
			(start -1.7018 -1.1176)
			(end -0.254 -1.1176)
			(stroke
				(width 0.1524)
				(type default)
			)
			(layer "B.SilkS")
		)
		(fp_line
			(start -1.7018 -1.1176)
			(end -1.7018 1.1176)
			(stroke
				(width 0.1524)
				(type default)
			)
			(layer "B.SilkS")
		)
		(fp_line
			(start 0 -0.7112)
			(end 0.254 -1.1176)
			(stroke
				(width 0.1524)
				(type default)
			)
			(layer "B.SilkS")
		)
		(fp_line
			(start 1.7018 1.1176)
			(end 1.7018 -1.1176)
			(stroke
				(width 0.1524)
				(type default)
			)
			(layer "B.SilkS")
		)
		(fp_line
			(start -1.7018 1.1176)
			(end 1.7018 1.1176)
			(stroke
				(width 0.1524)
				(type default)
			)
			(layer "B.SilkS")
		)
		(fp_poly
			(pts
				(xy 1.8161 -0.675386) (xy 2.4003 -0.446786) (xy 2.4003 -0.878586)
			)
			(stroke
				(width 0)
				(type default)
			)
			(fill yes)
			(layer "B.SilkS")
		)
		(fp_line
			(start 0.254 -1.1176)
			(end 1.5494 -1.1176)
			(stroke
				(width 0.1)
				(type default)
			)
			(layer "B.Fab")
		)
		(fp_line
			(start -0.254 -1.1176)
			(end 0.254 -1.1176)
			(stroke
				(width 0.1)
				(type default)
			)
			(layer "B.Fab")
		)
		(fp_line
			(start -1.5494 -1.1176)
			(end -0.254 -1.1176)
			(stroke
				(width 0.1)
				(type default)
			)
			(layer "B.Fab")
		)
		(fp_line
			(start -1.5494 -1.1176)
			(end -1.5494 1.1176)
			(stroke
				(width 0.1)
				(type default)
			)
			(layer "B.Fab")
		)
		(fp_line
			(start 1.5494 1.1176)
			(end 1.5494 -1.1176)
			(stroke
				(width 0.1)
				(type default)
			)
			(layer "B.Fab")
		)
		(fp_line
			(start -1.5494 1.1176)
			(end 1.5494 1.1176)
			(stroke
				(width 0.1)
				(type default)
			)
			(layer "B.Fab")
		)
		(fp_poly
			(pts
				(xy 1.8161 -0.675386) (xy 2.4003 -0.446786) (xy 2.4003 -0.878586)
			)
			(stroke
				(width 0)
				(type default)
			)
			(fill yes)
			(layer "B.Fab")
		)
		(pad "1" smd rect
			(at 0.962406 -0.649986)
			(size 0.3302 1.1684)
			(layers "B.Cu" "B.Mask" "B.Paste")
			(net "PWRGD_P5V_AUX")
		)
		(pad "2" smd rect
			(at 0.962406 0)
			(size 0.3302 1.1684)
			(layers "B.Cu" "B.Mask" "B.Paste")
			(net "PWRGD_P3V3_RGM")
		)
		(pad "3" smd rect
			(at 0.962406 0.649986)
			(size 0.3302 1.1684)
			(layers "B.Cu" "B.Mask" "B.Paste")
			(net "GND")
		)
		(pad "4" smd rect
			(at -0.962406 0.649986)
			(size 0.3302 1.1684)
			(layers "B.Cu" "B.Mask" "B.Paste")
			(net "EN_P1V2_AUX")
		)
		(pad "5" smd rect
			(at -0.962406 -0.649986)
			(size 0.3302 1.1684)
			(layers "B.Cu" "B.Mask" "B.Paste")
			(net "P3V3_LDO")
		)
	)
	(footprint ""
		(layer "B.Cu")
		(at 112.014 -58.42 90)
		(property "Reference" "X2"
			(at 1.99263 2.8448 0)
			(unlocked yes)
			(layer "B.SilkS")
			(effects
				(font
					(size 0.7874 0.5842)
					(thickness 0.1524)
				)
				(justify left mirror)
			)
		)
		(property "Value" ""
			(at 0 0 90)
			(layer "B.Fab")
			(effects
				(font
					(size 1.27 1.27)
				)
				(justify mirror)
			)
		)
		(property "Device Type" "TP_TDR_4P_FTS_TH-TP_TDR_4P_DIPA"
			(at -1.30175 1.27 0)
			(unlocked yes)
			(layer "B.Fab")
			(hide yes)
			(effects
				(font
					(size 0.635 0.4064)
					(thickness 0.1524)
				)
				(justify mirror)
			)
		)
		(property "User Part Number" "N_A"
			(at -1.30175 1.27 0)
			(unlocked yes)
			(layer "Cmts.User")
			(hide yes)
			(effects
				(font
					(size 0.635 0.4064)
					(thickness 0.1524)
				)
				(justify mirror)
			)
		)
		(duplicate_pad_numbers_are_jumpers no)
		(fp_line
			(start 0 -1.27)
			(end 0 -0.635)
			(stroke
				(width 0.1524)
				(type default)
			)
			(layer "B.SilkS")
		)
		(fp_line
			(start -2.54 -1.27)
			(end 0 -1.27)
			(stroke
				(width 0.1524)
				(type default)
			)
			(layer "B.SilkS")
		)
		(fp_line
			(start -2.54 -1.1303)
			(end -2.54 -1.27)
			(stroke
				(width 0.1524)
				(type default)
			)
			(layer "B.SilkS")
		)
		(fp_line
			(start 0 0.635)
			(end 0 1.905)
			(stroke
				(width 0.1524)
				(type default)
			)
			(layer "B.SilkS")
		)
		(fp_line
			(start -2.54 1.4097)
			(end -2.54 1.1303)
			(stroke
				(width 0.1524)
				(type default)
			)
			(layer "B.SilkS")
		)
		(fp_line
			(start 0 3.175)
			(end 0 3.81)
			(stroke
				(width 0.1524)
				(type default)
			)
			(layer "B.SilkS")
		)
		(fp_line
			(start 0 3.81)
			(end -2.54 3.81)
			(stroke
				(width 0.1524)
				(type default)
			)
			(layer "B.SilkS")
		)
		(fp_line
			(start -2.54 3.81)
			(end -2.54 3.6703)
			(stroke
				(width 0.1524)
				(type default)
			)
			(layer "B.SilkS")
		)
		(fp_poly
			(pts
				(xy 0.761746 0) (xy 2.285746 -0.762) (xy 2.285746 0.762)
			)
			(stroke
				(width 0)
				(type default)
			)
			(fill yes)
			(layer "B.SilkS")
		)
		(fp_line
			(start 0 -1.27)
			(end 0 3.81)
			(stroke
				(width 0.1)
				(type default)
			)
			(layer "B.Fab")
		)
		(fp_line
			(start -2.54 -1.27)
			(end 0 -1.27)
			(stroke
				(width 0.1)
				(type default)
			)
			(layer "B.Fab")
		)
		(fp_line
			(start 0 3.81)
			(end -2.54 3.81)
			(stroke
				(width 0.1)
				(type default)
			)
			(layer "B.Fab")
		)
		(fp_line
			(start -2.54 3.81)
			(end -2.54 -1.27)
			(stroke
				(width 0.1)
				(type default)
			)
			(layer "B.Fab")
		)
		(fp_poly
			(pts
				(xy 0.761746 0) (xy 2.285746 -0.762) (xy 2.285746 0.762)
			)
			(stroke
				(width 0)
				(type default)
			)
			(fill yes)
			(layer "B.Fab")
		)
		(pad "1" thru_hole circle
			(at 0 0 270)
			(size 1.0033 1.0033)
			(drill 0.249936)
			(layers "*.Cu" "*.Mask")
			(remove_unused_layers no)
			(net "TDR_DIFF_85_IN1_DP")
			(clearance 0.10795)
			(padstack
				(mode front_inner_back)
				(layer "Inner"
					(shape circle)
					(size 0.8001 0.8001)
					(clearance 0.1524)
				)
				(layer "B.Cu"
					(shape circle)
					(size 1.0033 1.0033)
					(thermal_gap 0.10795)
					(clearance 0.10795)
				)
			)
		)
		(pad "2" thru_hole circle
			(at -2.54 0 270)
			(size 1.9939 1.9939)
			(drill 0.249936)
			(layers "*.Cu" "*.Mask")
			(remove_unused_layers no)
			(net "GND_P1")
			(clearance 0.10795)
			(padstack
				(mode front_inner_back)
				(layer "Inner"
					(shape circle)
					(size 0.8001 0.8001)
					(clearance 0.1524)
				)
				(layer "B.Cu"
					(shape circle)
					(size 1.9939 1.9939)
					(thermal_gap 0.10795)
					(clearance 0.10795)
				)
			)
		)
		(pad "3" thru_hole circle
			(at -2.54 2.54 270)
			(size 1.9939 1.9939)
			(drill 0.249936)
			(layers "*.Cu" "*.Mask")
			(remove_unused_layers no)
			(net "GND_P1")
			(clearance 0.10795)
			(padstack
				(mode front_inner_back)
				(layer "Inner"
					(shape circle)
					(size 0.8001 0.8001)
					(clearance 0.1524)
				)
				(layer "B.Cu"
					(shape circle)
					(size 1.9939 1.9939)
					(thermal_gap 0.10795)
					(clearance 0.10795)
				)
			)
		)
		(pad "4" thru_hole circle
			(at 0 2.54 270)
			(size 1.0033 1.0033)
			(drill 0.249936)
			(layers "*.Cu" "*.Mask")
			(remove_unused_layers no)
			(net "TDR_DIFF_85_IN1_DN")
			(clearance 0.10795)
			(padstack
				(mode front_inner_back)
				(layer "Inner"
					(shape circle)
					(size 0.8001 0.8001)
					(clearance 0.1524)
				)
				(layer "B.Cu"
					(shape circle)
					(size 1.0033 1.0033)
					(thermal_gap 0.10795)
					(clearance 0.10795)
				)
			)
		)
	)
)
